(kicad_pcb
	(version 20260206)
	(generator "pcbnew")
	(generator_version "10.0")
	(general
		(thickness 1.6)
		(legacy_teardrops no)
	)
	(paper "A4")
	(title_block
		(title "peb — Lightning_PEB_BRD.brd")
		(comment 1 "Lightning (Wiwynn / Facebook NVMe JBOF) / footprint 1064 of 2563 (GF10), pads 114-200 of 200")
	)
	(layers
		(0 "F.Cu" signal "TOP")
		(4 "In1.Cu" signal "L2GND")
		(6 "In2.Cu" signal "L3")
		(8 "In3.Cu" signal "L4VCC")
		(10 "In4.Cu" signal "L5VCC")
		(12 "In5.Cu" signal "L6")
		(14 "In6.Cu" signal "L7GND")
		(2 "B.Cu" signal "BOTTOM")
		(9 "F.Adhes" user "F.Adhesive")
		(11 "B.Adhes" user "B.Adhesive")
		(13 "F.Paste" user "Package Geometry/Pastemask Top")
		(15 "B.Paste" user "Package Geometry/Pastemask Bottom")
		(5 "F.SilkS" user "Ref Des/Silkscreen Top")
		(7 "B.SilkS" user "Ref Des/Silkscreen Bottom")
		(1 "F.Mask" user "Board Geometry/Soldermask Top")
		(3 "B.Mask" user "Board Geometry/Soldermask Bottom")
		(17 "Dwgs.User" user "User.Drawings")
		(19 "Cmts.User" user "User.Comments")
		(21 "Eco1.User" user "User.Eco1")
		(23 "Eco2.User" user "User.Eco2")
		(25 "Edge.Cuts" user "Board Geometry/Outline")
		(27 "Margin" user)
		(31 "F.CrtYd" user "Package Geometry/Place Bound Top")
		(29 "B.CrtYd" user "Package Geometry/Place Bound Bottom")
		(35 "F.Fab" user "Ref Des/Assembly Top")
		(33 "B.Fab" user "Ref Des/Assembly Bottom")
	)
	(footprint ""
		(layer "F.Cu")
		(at 307.300122 -226.70008 180)
		(property "Reference" "GF10"
			(at 0 0 180)
			(layer "F.SilkS")
			(hide yes)
			(effects
				(font
					(size 1.27 1.27)
				)
			)
		)
		(property "Value" "GF-200P-8-GP-U1"
			(at -43.1673 -7.6327 180)
			(unlocked yes)
			(layer "F.Fab")
			(hide yes)
			(effects
				(font
					(size 1.016 1.016)
					(thickness 0.1524)
				)
			)
		)
		(property "Device Type" "GF-200P-8-U1"
			(at -43.1673 -9.1567 180)
			(unlocked yes)
			(layer "F.Fab")
			(hide yes)
			(effects
				(font
					(size 1.016 1.016)
					(thickness 0.1524)
				)
			)
		)
		(duplicate_pad_numbers_are_jumpers no)
		(pad "B14" smd rect
			(at -25.999948 -0.7747 180)
			(size 0.5588 2.3114)
			(drill
				(offset 0 -0.381)
			)
			(layers "F.Cu" "F.Mask" "F.Paste")
			(net "GND")
		)
		(pad "B15" smd rect
			(at -25.200102 -0.7747 180)
			(size 0.5588 2.3114)
			(drill
				(offset 0 -0.381)
			)
			(layers "F.Cu" "F.Mask" "F.Paste")
			(net "GND")
		)
		(pad "B16" smd rect
			(at -24.400002 -0.7747 180)
			(size 0.5588 2.3114)
			(drill
				(offset 0 -0.381)
			)
			(layers "F.Cu" "F.Mask" "F.Paste")
			(net "PCIE_RX_N19")
		)
		(pad "B17" smd rect
			(at -23.599902 -0.7747 180)
			(size 0.5588 2.3114)
			(drill
				(offset 0 -0.381)
			)
			(layers "F.Cu" "F.Mask" "F.Paste")
			(net "PCIE_RX_P19")
		)
		(pad "B18" smd rect
			(at -22.800056 -0.7747 180)
			(size 0.5588 2.3114)
			(drill
				(offset 0 -0.381)
			)
			(layers "F.Cu" "F.Mask" "F.Paste")
			(net "GND")
		)
		(pad "B19" smd rect
			(at -21.999956 -0.7747 180)
			(size 0.5588 2.3114)
			(drill
				(offset 0 -0.381)
			)
			(layers "F.Cu" "F.Mask" "F.Paste")
			(net "GND")
		)
		(pad "B20" smd rect
			(at -21.20011 -0.7747 180)
			(size 0.5588 2.3114)
			(drill
				(offset 0 -0.381)
			)
			(layers "F.Cu" "F.Mask" "F.Paste")
			(net "PCIE_RX_N20")
		)
		(pad "B21" smd rect
			(at -20.40001 -0.7747 180)
			(size 0.5588 2.3114)
			(drill
				(offset 0 -0.381)
			)
			(layers "F.Cu" "F.Mask" "F.Paste")
			(net "PCIE_RX_P20")
		)
		(pad "B22" smd rect
			(at -19.59991 -0.7747 180)
			(size 0.5588 2.3114)
			(drill
				(offset 0 -0.381)
			)
			(layers "F.Cu" "F.Mask" "F.Paste")
			(net "GND")
		)
		(pad "B23" smd rect
			(at -18.800064 -0.7747 180)
			(size 0.5588 2.3114)
			(drill
				(offset 0 -0.381)
			)
			(layers "F.Cu" "F.Mask" "F.Paste")
			(net "GND")
		)
		(pad "B24" smd rect
			(at -17.999964 -0.7747 180)
			(size 0.5588 2.3114)
			(drill
				(offset 0 -0.381)
			)
			(layers "F.Cu" "F.Mask" "F.Paste")
			(net "PCIE_RX_N21")
		)
		(pad "B25" smd rect
			(at -17.200118 -0.7747 180)
			(size 0.5588 2.3114)
			(drill
				(offset 0 -0.381)
			)
			(layers "F.Cu" "F.Mask" "F.Paste")
			(net "PCIE_RX_P21")
		)
		(pad "B26" smd rect
			(at -16.400018 -0.7747 180)
			(size 0.5588 2.3114)
			(drill
				(offset 0 -0.381)
			)
			(layers "F.Cu" "F.Mask" "F.Paste")
			(net "GND")
		)
		(pad "B27" smd rect
			(at -15.599918 -0.7747 180)
			(size 0.5588 2.3114)
			(drill
				(offset 0 -0.381)
			)
			(layers "F.Cu" "F.Mask" "F.Paste")
			(net "GND")
		)
		(pad "B28" smd rect
			(at -14.800072 -0.7747 180)
			(size 0.5588 2.3114)
			(drill
				(offset 0 -0.381)
			)
			(layers "F.Cu" "F.Mask" "F.Paste")
			(net "PCIE_RX_N22")
		)
		(pad "B29" smd rect
			(at -13.999972 -0.7747 180)
			(size 0.5588 2.3114)
			(drill
				(offset 0 -0.381)
			)
			(layers "F.Cu" "F.Mask" "F.Paste")
			(net "PCIE_RX_P22")
		)
		(pad "B30" smd rect
			(at -13.200126 -0.7747 180)
			(size 0.5588 2.3114)
			(drill
				(offset 0 -0.381)
			)
			(layers "F.Cu" "F.Mask" "F.Paste")
			(net "GND")
		)
		(pad "B31" smd rect
			(at -12.400026 -0.7747 180)
			(size 0.5588 2.3114)
			(drill
				(offset 0 -0.381)
			)
			(layers "F.Cu" "F.Mask" "F.Paste")
			(net "GND")
		)
		(pad "B32" smd rect
			(at -11.599926 -0.7747 180)
			(size 0.5588 2.3114)
			(drill
				(offset 0 -0.381)
			)
			(layers "F.Cu" "F.Mask" "F.Paste")
			(net "PCIE_RX_N23")
		)
		(pad "B33" smd rect
			(at -10.80008 -0.7747 180)
			(size 0.5588 2.3114)
			(drill
				(offset 0 -0.381)
			)
			(layers "F.Cu" "F.Mask" "F.Paste")
			(net "PCIE_RX_P23")
		)
		(pad "B34" smd rect
			(at -9.99998 -0.7747 180)
			(size 0.5588 2.3114)
			(drill
				(offset 0 -0.381)
			)
			(layers "F.Cu" "F.Mask" "F.Paste")
			(net "GND")
		)
		(pad "B35" smd rect
			(at -9.19988 -0.7747 180)
			(size 0.5588 2.3114)
			(drill
				(offset 0 -0.381)
			)
			(layers "F.Cu" "F.Mask" "F.Paste")
			(net "GND")
		)
		(pad "B36" smd rect
			(at -8.400034 -0.7747 180)
			(size 0.5588 2.3114)
			(drill
				(offset 0 -0.381)
			)
			(layers "F.Cu" "F.Mask" "F.Paste")
			(net "PCIE_RX_N24")
		)
		(pad "B37" smd rect
			(at -7.599934 -0.7747 180)
			(size 0.5588 2.3114)
			(drill
				(offset 0 -0.381)
			)
			(layers "F.Cu" "F.Mask" "F.Paste")
			(net "PCIE_RX_P24")
		)
		(pad "B38" smd rect
			(at -6.800088 -0.7747 180)
			(size 0.5588 2.3114)
			(drill
				(offset 0 -0.381)
			)
			(layers "F.Cu" "F.Mask" "F.Paste")
			(net "GND")
		)
		(pad "B39" smd rect
			(at -5.999988 -0.7747 180)
			(size 0.5588 2.3114)
			(drill
				(offset 0 -0.381)
			)
			(layers "F.Cu" "F.Mask" "F.Paste")
			(net "GND")
		)
		(pad "B40" smd rect
			(at -5.199888 -0.7747 180)
			(size 0.5588 2.3114)
			(drill
				(offset 0 -0.381)
			)
			(layers "F.Cu" "F.Mask" "F.Paste")
			(net "PCIE_RX_N25")
		)
		(pad "B41" smd rect
			(at -4.400042 -0.7747 180)
			(size 0.5588 2.3114)
			(drill
				(offset 0 -0.381)
			)
			(layers "F.Cu" "F.Mask" "F.Paste")
			(net "PCIE_RX_P25")
		)
		(pad "B42" smd rect
			(at -3.599942 -0.7747 180)
			(size 0.5588 2.3114)
			(drill
				(offset 0 -0.381)
			)
			(layers "F.Cu" "F.Mask" "F.Paste")
			(net "GND")
		)
		(pad "B43" smd rect
			(at -2.800096 -0.7747 180)
			(size 0.5588 2.3114)
			(drill
				(offset 0 -0.381)
			)
			(layers "F.Cu" "F.Mask" "F.Paste")
			(net "SSD_PERST#14_R")
		)
		(pad "B44" smd rect
			(at -1.999996 -0.7747 180)
			(size 0.5588 2.3114)
			(drill
				(offset 0 -0.381)
			)
			(layers "F.Cu" "F.Mask" "F.Paste")
			(net "SSD_PERST#4_R")
		)
		(pad "B45" smd rect
			(at 1.999996 -0.7747 180)
			(size 0.5588 2.3114)
			(drill
				(offset 0 -0.381)
			)
			(layers "F.Cu" "F.Mask" "F.Paste")
			(net "GND")
		)
		(pad "B46" smd rect
			(at 2.800096 -0.7747 180)
			(size 0.5588 2.3114)
			(drill
				(offset 0 -0.381)
			)
			(layers "F.Cu" "F.Mask" "F.Paste")
			(net "PCIE_RX_N26")
		)
		(pad "B47" smd rect
			(at 3.599942 -0.7747 180)
			(size 0.5588 2.3114)
			(drill
				(offset 0 -0.381)
			)
			(layers "F.Cu" "F.Mask" "F.Paste")
			(net "PCIE_RX_P26")
		)
		(pad "B48" smd rect
			(at 4.400042 -0.7747 180)
			(size 0.5588 2.3114)
			(drill
				(offset 0 -0.381)
			)
			(layers "F.Cu" "F.Mask" "F.Paste")
			(net "GND")
		)
		(pad "B49" smd rect
			(at 5.199888 -0.7747 180)
			(size 0.5588 2.3114)
			(drill
				(offset 0 -0.381)
			)
			(layers "F.Cu" "F.Mask" "F.Paste")
			(net "GND")
		)
		(pad "B50" smd rect
			(at 5.999988 -0.7747 180)
			(size 0.5588 2.3114)
			(drill
				(offset 0 -0.381)
			)
			(layers "F.Cu" "F.Mask" "F.Paste")
			(net "PCIE_RX_N27")
		)
		(pad "B51" smd rect
			(at 6.800088 -0.7747 180)
			(size 0.5588 2.3114)
			(drill
				(offset 0 -0.381)
			)
			(layers "F.Cu" "F.Mask" "F.Paste")
			(net "PCIE_RX_P27")
		)
		(pad "B52" smd rect
			(at 7.599934 -0.7747 180)
			(size 0.5588 2.3114)
			(drill
				(offset 0 -0.381)
			)
			(layers "F.Cu" "F.Mask" "F.Paste")
			(net "GND")
		)
		(pad "B53" smd rect
			(at 8.400034 -0.7747 180)
			(size 0.5588 2.3114)
			(drill
				(offset 0 -0.381)
			)
			(layers "F.Cu" "F.Mask" "F.Paste")
			(net "SSD_PRSNT#4_R")
		)
		(pad "B54" smd rect
			(at 9.19988 -0.7747 180)
			(size 0.5588 2.3114)
			(drill
				(offset 0 -0.381)
			)
			(layers "F.Cu" "F.Mask" "F.Paste")
			(net "SSD_ATNLED#4_R")
		)
		(pad "B55" smd rect
			(at 9.99998 -0.7747 180)
			(size 0.5588 2.3114)
			(drill
				(offset 0 -0.381)
			)
			(layers "F.Cu" "F.Mask" "F.Paste")
			(net "SSD_PWREN4_R")
		)
		(pad "B56" smd rect
			(at 10.80008 -0.7747 180)
			(size 0.5588 2.3114)
			(drill
				(offset 0 -0.381)
			)
			(layers "F.Cu" "F.Mask" "F.Paste")
			(net "GND")
		)
		(pad "B57" smd rect
			(at 11.599926 -0.7747 180)
			(size 0.5588 2.3114)
			(drill
				(offset 0 -0.381)
			)
			(layers "F.Cu" "F.Mask" "F.Paste")
			(net "PCIE_RX_N28")
		)
		(pad "B58" smd rect
			(at 12.400026 -0.7747 180)
			(size 0.5588 2.3114)
			(drill
				(offset 0 -0.381)
			)
			(layers "F.Cu" "F.Mask" "F.Paste")
			(net "PCIE_RX_P28")
		)
		(pad "B59" smd rect
			(at 13.200126 -0.7747 180)
			(size 0.5588 2.3114)
			(drill
				(offset 0 -0.381)
			)
			(layers "F.Cu" "F.Mask" "F.Paste")
			(net "GND")
		)
		(pad "B60" smd rect
			(at 13.999972 -0.7747 180)
			(size 0.5588 2.3114)
			(drill
				(offset 0 -0.381)
			)
			(layers "F.Cu" "F.Mask" "F.Paste")
			(net "GND")
		)
		(pad "B61" smd rect
			(at 14.800072 -0.7747 180)
			(size 0.5588 2.3114)
			(drill
				(offset 0 -0.381)
			)
			(layers "F.Cu" "F.Mask" "F.Paste")
			(net "PCIE_RX_N29")
		)
		(pad "B62" smd rect
			(at 15.599918 -0.7747 180)
			(size 0.5588 2.3114)
			(drill
				(offset 0 -0.381)
			)
			(layers "F.Cu" "F.Mask" "F.Paste")
			(net "PCIE_RX_P29")
		)
		(pad "B63" smd rect
			(at 16.400018 -0.7747 180)
			(size 0.5588 2.3114)
			(drill
				(offset 0 -0.381)
			)
			(layers "F.Cu" "F.Mask" "F.Paste")
			(net "GND")
		)
		(pad "B64" smd rect
			(at 17.200118 -0.7747 180)
			(size 0.5588 2.3114)
			(drill
				(offset 0 -0.381)
			)
			(layers "F.Cu" "F.Mask" "F.Paste")
			(net "GND")
		)
		(pad "B65" smd rect
			(at 17.999964 -0.7747 180)
			(size 0.5588 2.3114)
			(drill
				(offset 0 -0.381)
			)
			(layers "F.Cu" "F.Mask" "F.Paste")
			(net "PCIE_RX_N30")
		)
		(pad "B66" smd rect
			(at 18.800064 -0.7747 180)
			(size 0.5588 2.3114)
			(drill
				(offset 0 -0.381)
			)
			(layers "F.Cu" "F.Mask" "F.Paste")
			(net "PCIE_RX_P30")
		)
		(pad "B67" smd rect
			(at 19.59991 -0.7747 180)
			(size 0.5588 2.3114)
			(drill
				(offset 0 -0.381)
			)
			(layers "F.Cu" "F.Mask" "F.Paste")
			(net "GND")
		)
		(pad "B68" smd rect
			(at 20.40001 -0.7747 180)
			(size 0.5588 2.3114)
			(drill
				(offset 0 -0.381)
			)
			(layers "F.Cu" "F.Mask" "F.Paste")
			(net "GND")
		)
		(pad "B69" smd rect
			(at 21.20011 -0.7747 180)
			(size 0.5588 2.3114)
			(drill
				(offset 0 -0.381)
			)
			(layers "F.Cu" "F.Mask" "F.Paste")
			(net "PCIE_RX_N31")
		)
		(pad "B70" smd rect
			(at 21.999956 -0.7747 180)
			(size 0.5588 2.3114)
			(drill
				(offset 0 -0.381)
			)
			(layers "F.Cu" "F.Mask" "F.Paste")
			(net "PCIE_RX_P31")
		)
		(pad "B71" smd rect
			(at 22.800056 -0.7747 180)
			(size 0.5588 2.3114)
			(drill
				(offset 0 -0.381)
			)
			(layers "F.Cu" "F.Mask" "F.Paste")
			(net "GND")
		)
		(pad "B72" smd rect
			(at 23.599902 -0.7747 180)
			(size 0.5588 2.3114)
			(drill
				(offset 0 -0.381)
			)
			(layers "F.Cu" "F.Mask" "F.Paste")
			(net "GND")
		)
		(pad "B73" smd rect
			(at 24.400002 -0.7747 180)
			(size 0.5588 2.3114)
			(drill
				(offset 0 -0.381)
			)
			(layers "F.Cu" "F.Mask" "F.Paste")
			(net "PCIE_RX_N32")
		)
		(pad "B74" smd rect
			(at 25.200102 -0.7747 180)
			(size 0.5588 2.3114)
			(drill
				(offset 0 -0.381)
			)
			(layers "F.Cu" "F.Mask" "F.Paste")
			(net "PCIE_RX_P32")
		)
		(pad "B75" smd rect
			(at 25.999948 -0.7747 180)
			(size 0.5588 2.3114)
			(drill
				(offset 0 -0.381)
			)
			(layers "F.Cu" "F.Mask" "F.Paste")
			(net "GND")
		)
		(pad "B76" smd rect
			(at 26.800048 -0.7747 180)
			(size 0.5588 2.3114)
			(drill
				(offset 0 -0.381)
			)
			(layers "F.Cu" "F.Mask" "F.Paste")
			(net "GND")
		)
		(pad "B77" smd rect
			(at 27.599894 -0.7747 180)
			(size 0.5588 2.3114)
			(drill
				(offset 0 -0.381)
			)
			(layers "F.Cu" "F.Mask" "F.Paste")
			(net "PCIE_RX_N33")
		)
		(pad "B78" smd rect
			(at 28.399994 -0.7747 180)
			(size 0.5588 2.3114)
			(drill
				(offset 0 -0.381)
			)
			(layers "F.Cu" "F.Mask" "F.Paste")
			(net "PCIE_RX_P33")
		)
		(pad "B79" smd rect
			(at 29.200094 -0.7747 180)
			(size 0.5588 2.3114)
			(drill
				(offset 0 -0.381)
			)
			(layers "F.Cu" "F.Mask" "F.Paste")
			(net "GND")
		)
		(pad "B80" smd rect
			(at 29.99994 -0.7747 180)
			(size 0.5588 2.3114)
			(drill
				(offset 0 -0.381)
			)
			(layers "F.Cu" "F.Mask" "F.Paste")
			(net "GND")
		)
		(pad "B81" smd rect
			(at 30.80004 -0.7747 180)
			(size 0.5588 2.3114)
			(drill
				(offset 0 -0.381)
			)
			(layers "F.Cu" "F.Mask" "F.Paste")
			(net "PCIE_RX_N34")
		)
		(pad "B82" smd rect
			(at 31.599886 -0.7747 180)
			(size 0.5588 2.3114)
			(drill
				(offset 0 -0.381)
			)
			(layers "F.Cu" "F.Mask" "F.Paste")
			(net "PCIE_RX_P34")
		)
		(pad "B83" smd rect
			(at 32.399986 -0.7747 180)
			(size 0.5588 2.3114)
			(drill
				(offset 0 -0.381)
			)
			(layers "F.Cu" "F.Mask" "F.Paste")
			(net "GND")
		)
		(pad "B84" smd rect
			(at 33.200086 -0.7747 180)
			(size 0.5588 2.3114)
			(drill
				(offset 0 -0.381)
			)
			(layers "F.Cu" "F.Mask" "F.Paste")
			(net "GND")
		)
		(pad "B85" smd rect
			(at 33.999932 -0.7747 180)
			(size 0.5588 2.3114)
			(drill
				(offset 0 -0.381)
			)
			(layers "F.Cu" "F.Mask" "F.Paste")
			(net "PCIE_RX_N35")
		)
		(pad "B86" smd rect
			(at 34.800032 -0.7747 180)
			(size 0.5588 2.3114)
			(drill
				(offset 0 -0.381)
			)
			(layers "F.Cu" "F.Mask" "F.Paste")
			(net "PCIE_RX_P35")
		)
		(pad "B87" smd rect
			(at 35.599878 -0.7747 180)
			(size 0.5588 2.3114)
			(drill
				(offset 0 -0.381)
			)
			(layers "F.Cu" "F.Mask" "F.Paste")
			(net "GND")
		)
		(pad "B88" smd rect
			(at 36.399978 -0.7747 180)
			(size 0.5588 2.3114)
			(drill
				(offset 0 -0.381)
			)
			(layers "F.Cu" "F.Mask" "F.Paste")
			(net "SSD_PRSNT#8_R")
		)
		(pad "B89" smd rect
			(at 37.200078 -0.7747 180)
			(size 0.5588 2.3114)
			(drill
				(offset 0 -0.381)
			)
			(layers "F.Cu" "F.Mask" "F.Paste")
			(net "SSD_ATNLED#8_R")
		)
		(pad "B90" smd rect
			(at 37.999924 -0.7747 180)
			(size 0.5588 2.3114)
			(drill
				(offset 0 -0.381)
			)
			(layers "F.Cu" "F.Mask" "F.Paste")
			(net "SSD_PWREN8_R")
		)
		(pad "B91" smd rect
			(at 38.800024 -0.7747 180)
			(size 0.5588 2.3114)
			(drill
				(offset 0 -0.381)
			)
			(layers "F.Cu" "F.Mask" "F.Paste")
			(net "SSD_PERST#8_R")
		)
		(pad "B92" smd rect
			(at 39.600124 -0.7747 180)
			(size 0.5588 2.3114)
			(drill
				(offset 0 -0.381)
			)
			(layers "F.Cu" "F.Mask" "F.Paste")
			(net "GND")
		)
		(pad "B93" smd rect
			(at 40.39997 -0.7747 180)
			(size 0.5588 2.3114)
			(drill
				(offset 0 -0.381)
			)
			(layers "F.Cu" "F.Mask" "F.Paste")
			(net "PCIE_RX_N36")
		)
		(pad "B94" smd rect
			(at 41.20007 -0.7747 180)
			(size 0.5588 2.3114)
			(drill
				(offset 0 -0.381)
			)
			(layers "F.Cu" "F.Mask" "F.Paste")
			(net "PCIE_RX_P36")
		)
		(pad "B95" smd rect
			(at 41.999916 -0.7747 180)
			(size 0.5588 2.3114)
			(drill
				(offset 0 -0.381)
			)
			(layers "F.Cu" "F.Mask" "F.Paste")
			(net "GND")
		)
		(pad "B96" smd rect
			(at 42.800016 -0.7747 180)
			(size 0.5588 2.3114)
			(drill
				(offset 0 -0.381)
			)
			(layers "F.Cu" "F.Mask" "F.Paste")
			(net "GND")
		)
		(pad "B97" smd rect
			(at 43.600116 -0.7747 180)
			(size 0.5588 2.3114)
			(drill
				(offset 0 -0.381)
			)
			(layers "F.Cu" "F.Mask" "F.Paste")
			(net "PCIE_RX_N37")
		)
		(pad "B98" smd rect
			(at 44.399962 -0.7747 180)
			(size 0.5588 2.3114)
			(drill
				(offset 0 -0.381)
			)
			(layers "F.Cu" "F.Mask" "F.Paste")
			(net "PCIE_RX_P37")
		)
		(pad "B99" smd rect
			(at 45.200062 -0.7747 180)
			(size 0.5588 2.3114)
			(drill
				(offset 0 -0.381)
			)
			(layers "F.Cu" "F.Mask" "F.Paste")
			(net "GND")
		)
		(pad "B100" smd rect
			(at 45.999908 -0.7747 180)
			(size 0.5588 2.3114)
			(drill
				(offset 0 -0.381)
			)
			(layers "F.Cu" "F.Mask" "F.Paste")
			(net "I2C_MUX_RESET_PEB")
		)
	)
)
